# BASEBOARD_FAB2 (Tioga Pass) — schematic netlist excerpt (pin names and nets, part order shuffled) for the footprints in the layout excerpt that follows; sources: Cadence DE-HDL packaged netlist, KiCad conversion of Wiwynn_Tioga_Pass_MB.brd

C1M18  CAP  0.22UF 16V 10% X7R  pkg 0402  page 106 : A = P3E_CPU0_PE3_OCP_TXP<9> ; B = P3E_OCP_CPU0_PE3_C_TXP<9>
C3M24  CAP  10UF 4V 20% X6S  pkg 0603LF  page 127 : A = P1V05_PCH_STBY_ISCLK_PLL ; B = GND
R25W96  RES  4.75K 1% CHIP  pkg 0402  page 150 : A = P3V3_STBY ; B = SPI_BMC_BT_DO

(kicad_pcb
	(version 20260206)
	(generator "pcbnew")
	(generator_version "10.0")
	(general
		(thickness 1.6)
		(legacy_teardrops no)
	)
	(paper "A4")
	(title_block
		(title "Wiwynn_Tioga_Pass_MB.brd")
		(comment 1 "Tioga Pass / footprints 3730-3732 of 4770")
	)
	(layers
		(0 "F.Cu" signal "TOP")
		(4 "In1.Cu" signal "L2GND")
		(6 "In2.Cu" signal "L3")
		(8 "In3.Cu" signal "L4GND")
		(10 "In4.Cu" signal "L5")
		(12 "In5.Cu" signal "L6GND")
		(14 "In6.Cu" signal "L7VCC")
		(16 "In7.Cu" signal "L8VCC")
		(18 "In8.Cu" signal "L9GND")
		(20 "In9.Cu" signal "L10")
		(22 "In10.Cu" signal "L11GND")
		(24 "In11.Cu" signal "L12")
		(26 "In12.Cu" signal "L13GND")
		(2 "B.Cu" signal "BOTTOM")
		(9 "F.Adhes" user "F.Adhesive")
		(11 "B.Adhes" user "B.Adhesive")
		(13 "F.Paste" user "Package Geometry/Pastemask Top")
		(15 "B.Paste" user "Package Geometry/Pastemask Bottom")
		(5 "F.SilkS" user "Ref Des/Silkscreen Top")
		(7 "B.SilkS" user "Ref Des/Silkscreen Bottom")
		(1 "F.Mask" user "Board Geometry/Soldermask Top")
		(3 "B.Mask" user "Board Geometry/Soldermask Bottom")
		(17 "Dwgs.User" user "User.Drawings")
		(19 "Cmts.User" user "User.Comments")
		(21 "Eco1.User" user "User.Eco1")
		(23 "Eco2.User" user "User.Eco2")
		(25 "Edge.Cuts" user "Board Geometry/Outline")
		(27 "Margin" user)
		(31 "F.CrtYd" user "Package Geometry/Place Bound Top")
		(29 "B.CrtYd" user "Package Geometry/Place Bound Bottom")
		(35 "F.Fab" user "Ref Des/Assembly Top")
		(33 "B.Fab" user "Ref Des/Assembly Bottom")
	)
	(footprint ""
		(layer "B.Cu")
		(at 447.04 -116.49202)
		(property "Reference" "C1M18"
			(at 0 0 0)
			(layer "B.SilkS")
			(hide yes)
			(effects
				(font
					(size 1.27 1.27)
				)
				(justify mirror)
			)
		)
		(property "Value" ""
			(at 0 0 0)
			(layer "B.Fab")
			(effects
				(font
					(size 1.27 1.27)
				)
				(justify mirror)
			)
		)
		(duplicate_pad_numbers_are_jumpers no)
		(fp_rect
			(start -0.3048 0.9906)
			(end 0.3048 -0.1016)
			(stroke
				(width 0)
				(type default)
			)
			(fill no)
			(layer "B.CrtYd")
		)
		(fp_line
			(start -0.3048 -0.1016)
			(end 0.3048 -0.1016)
			(stroke
				(width 0.1)
				(type default)
			)
			(layer "B.Fab")
		)
		(fp_line
			(start -0.3048 0.9906)
			(end -0.3048 -0.1016)
			(stroke
				(width 0.1)
				(type default)
			)
			(layer "B.Fab")
		)
		(fp_line
			(start 0.3048 -0.1016)
			(end 0.3048 0.9906)
			(stroke
				(width 0.1)
				(type default)
			)
			(layer "B.Fab")
		)
		(fp_line
			(start 0.3048 0.9906)
			(end -0.3048 0.9906)
			(stroke
				(width 0.1)
				(type default)
			)
			(layer "B.Fab")
		)
		(pad "1" smd rect
			(at 0 0 180)
			(size 0.508 0.508)
			(layers "B.Cu" "B.Mask" "B.Paste")
			(net "P3E_CPU0_PE3_OCP_TXP<9>")
		)
		(pad "2" smd rect
			(at 0 0.889 180)
			(size 0.508 0.508)
			(layers "B.Cu" "B.Mask" "B.Paste")
			(net "P3E_OCP_CPU0_PE3_C_TXP<9>")
		)
		(zone
			(layer "B.Cu")
			(hatch none 0.5)
			(connect_pads
				(clearance 0)
			)
			(min_thickness 0.25)
			(keepout
				(tracks allowed)
				(vias not_allowed)
				(pads allowed)
				(copperpour not_allowed)
				(footprints allowed)
			)
			(placement
				(enabled no)
				(sheetname "")
			)
			(fill
				(thermal_gap 0.5)
				(thermal_bridge_width 0.5)
				(island_removal_mode 0)
			)
			(polygon
				(pts
					(xy 446.786 -115.85702) (xy 447.294 -115.85702) (xy 447.294 -116.23802) (xy 446.786 -116.23802)
				)
			)
		)
		(zone
			(layer "B.Cu")
			(hatch none 0.5)
			(connect_pads
				(clearance 0)
			)
			(min_thickness 0.25)
			(keepout
				(tracks not_allowed)
				(vias allowed)
				(pads allowed)
				(copperpour not_allowed)
				(footprints allowed)
			)
			(placement
				(enabled no)
				(sheetname "")
			)
			(fill
				(thermal_gap 0.5)
				(thermal_bridge_width 0.5)
				(island_removal_mode 0)
			)
			(polygon
				(pts
					(xy 446.786 -115.85702) (xy 447.294 -115.85702) (xy 447.294 -116.23802) (xy 446.786 -116.23802)
				)
			)
		)
	)
	(footprint ""
		(layer "B.Cu")
		(at 372.9482 -133.8072 -90)
		(property "Reference" "C3M24"
			(at 0 0 90)
			(layer "B.SilkS")
			(hide yes)
			(effects
				(font
					(size 1.27 1.27)
				)
				(justify mirror)
			)
		)
		(property "Value" ""
			(at 0 0 90)
			(layer "B.Fab")
			(effects
				(font
					(size 1.27 1.27)
				)
				(justify mirror)
			)
		)
		(duplicate_pad_numbers_are_jumpers no)
		(fp_rect
			(start 0.4953 1.6002)
			(end -0.4953 -0.2032)
			(stroke
				(width 0)
				(type default)
			)
			(fill no)
			(layer "B.CrtYd")
		)
		(fp_line
			(start -0.4953 1.6002)
			(end 0.4953 1.6002)
			(stroke
				(width 0.1)
				(type default)
			)
			(layer "B.Fab")
		)
		(fp_line
			(start 0.4953 1.6002)
			(end 0.4953 -0.2032)
			(stroke
				(width 0.1)
				(type default)
			)
			(layer "B.Fab")
		)
		(fp_line
			(start -0.4953 -0.2032)
			(end -0.4953 1.6002)
			(stroke
				(width 0.1)
				(type default)
			)
			(layer "B.Fab")
		)
		(fp_line
			(start 0.4953 -0.2032)
			(end -0.4953 -0.2032)
			(stroke
				(width 0.1)
				(type default)
			)
			(layer "B.Fab")
		)
		(pad "1" smd rect
			(at 0 0 90)
			(size 0.762 0.889)
			(layers "B.Cu" "B.Mask" "B.Paste")
			(net "P1V05_PCH_STBY_ISCLK_PLL")
		)
		(pad "2" smd rect
			(at 0 1.397 90)
			(size 0.762 0.889)
			(layers "B.Cu" "B.Mask" "B.Paste")
			(net "GND")
		)
		(zone
			(layer "B.Cu")
			(hatch none 0.5)
			(connect_pads
				(clearance 0)
			)
			(min_thickness 0.25)
			(keepout
				(tracks not_allowed)
				(vias allowed)
				(pads allowed)
				(copperpour not_allowed)
				(footprints allowed)
			)
			(placement
				(enabled no)
				(sheetname "")
			)
			(fill
				(thermal_gap 0.5)
				(thermal_bridge_width 0.5)
				(island_removal_mode 0)
			)
			(polygon
				(pts
					(xy 371.9957 -133.4262) (xy 372.5037 -133.4262) (xy 372.5037 -134.1882) (xy 371.9957 -134.1882)
				)
			)
		)
	)
	(footprint ""
		(layer "B.Cu")
		(at 420.923466 -45.536612 90)
		(property "Reference" "R25W96"
			(at 0.8382 -0.67818 90)
			(unlocked yes)
			(layer "B.SilkS")
			(effects
				(font
					(size 0.4064 0.254)
					(thickness 0.1524)
				)
				(justify left mirror)
			)
		)
		(property "Value" ""
			(at 0 0 90)
			(layer "B.Fab")
			(effects
				(font
					(size 1.27 1.27)
				)
				(justify mirror)
			)
		)
		(duplicate_pad_numbers_are_jumpers no)
		(fp_poly
			(pts
				(xy 0.2794 -0.1016) (xy -0.2794 -0.1016) (xy -0.2794 0.9906) (xy 0.2794 0.9906)
			)
			(stroke
				(width 0)
				(type default)
			)
			(fill no)
			(layer "B.CrtYd")
		)
		(fp_line
			(start 0.2794 -0.1016)
			(end 0.2794 0.9906)
			(stroke
				(width 0.1)
				(type default)
			)
			(layer "B.Fab")
		)
		(fp_line
			(start -0.2794 -0.1016)
			(end 0.2794 -0.1016)
			(stroke
				(width 0.1)
				(type default)
			)
			(layer "B.Fab")
		)
		(fp_line
			(start 0.2794 0.9906)
			(end -0.2794 0.9906)
			(stroke
				(width 0.1)
				(type default)
			)
			(layer "B.Fab")
		)
		(fp_line
			(start -0.2794 0.9906)
			(end -0.2794 -0.1016)
			(stroke
				(width 0.1)
				(type default)
			)
			(layer "B.Fab")
		)
		(pad "1" smd rect
			(at 0 0 270)
			(size 0.508 0.508)
			(layers "B.Cu" "B.Mask" "B.Paste")
			(net "P3V3_STBY")
		)
		(pad "2" smd rect
			(at 0 0.889 270)
			(size 0.508 0.508)
			(layers "B.Cu" "B.Mask" "B.Paste")
			(net "SPI_BMC_BT_DO")
		)
		(zone
			(layer "B.Cu")
			(hatch none 0.5)
			(connect_pads
				(clearance 0)
			)
			(min_thickness 0.25)
			(keepout
				(tracks allowed)
				(vias not_allowed)
				(pads allowed)
				(copperpour not_allowed)
				(footprints allowed)
			)
			(placement
				(enabled no)
				(sheetname "")
			)
			(fill
				(thermal_gap 0.5)
				(thermal_bridge_width 0.5)
				(island_removal_mode 0)
			)
			(polygon
				(pts
					(xy 421.177466 -45.790612) (xy 421.177466 -45.282612) (xy 421.558466 -45.282612) (xy 421.558466 -45.790612)
				)
			)
		)
		(zone
			(layer "B.Cu")
			(hatch none 0.5)
			(connect_pads
				(clearance 0)
			)
			(min_thickness 0.25)
			(keepout
				(tracks not_allowed)
				(vias allowed)
				(pads allowed)
				(copperpour not_allowed)
				(footprints allowed)
			)
			(placement
				(enabled no)
				(sheetname "")
			)
			(fill
				(thermal_gap 0.5)
				(thermal_bridge_width 0.5)
				(island_removal_mode 0)
			)
			(polygon
				(pts
					(xy 421.558466 -45.790612) (xy 421.558466 -45.282612) (xy 421.177466 -45.282612) (xy 421.177466 -45.790612)
				)
			)
		)
	)
)
